# S9S_MB_2U (Grand Teton) — schematic netlist excerpt (pin names and nets, part order shuffled) for the footprints in the layout excerpt that follows; sources: Cadence DE-HDL packaged netlist, KiCad conversion of 03242023_DA0F0TMBIJ0_F0T_Motherboard_J_brd_V01_OCP.brd

R2356  Q_RES  10K 1% CHIP  pkg 0402LF  page 258 : A = P5V_AUX_VCC ; B = PWRGD_P5V_AUX_R
C377  Q_CAP  47UF 4V 20% X6S  pkg C0805  page 76 : A = PVCCIN_CPU0 ; B = GND
R2413  Q_RES  0 5% CHIP  pkg 0402LF  page 240 : A = SMB_2_BMC_GPU_SCL ; B = SMB_PCIE2_3V3AUX_SCL_R0

(kicad_pcb
	(version 20260206)
	(generator "pcbnew")
	(generator_version "10.0")
	(general
		(thickness 1.6)
		(legacy_teardrops no)
	)
	(paper "A4")
	(title_block
		(title "03242023_DA0F0TMBIJ0_F0T_Motherboard_J_brd_V01_OCP.brd")
		(comment 1 "Grand Teton / footprints 5617-5619 of 6105")
	)
	(layers
		(0 "F.Cu" signal "TOP")
		(4 "In1.Cu" signal "GND")
		(6 "In2.Cu" signal "IN1")
		(8 "In3.Cu" signal "GND1")
		(10 "In4.Cu" signal "IN2")
		(12 "In5.Cu" signal "GND2")
		(14 "In6.Cu" signal "IN3")
		(16 "In7.Cu" signal "GND3")
		(18 "In8.Cu" signal "VCC")
		(20 "In9.Cu" signal "VCC1")
		(22 "In10.Cu" signal "GND4")
		(24 "In11.Cu" signal "IN4")
		(26 "In12.Cu" signal "GND5")
		(28 "In13.Cu" signal "IN5")
		(30 "In14.Cu" signal "GND6")
		(32 "In15.Cu" signal "IN6")
		(34 "In16.Cu" signal "GND7")
		(2 "B.Cu" signal "BOTTOM")
		(9 "F.Adhes" user "F.Adhesive")
		(11 "B.Adhes" user "B.Adhesive")
		(13 "F.Paste" user "Package Geometry/Pastemask Top")
		(15 "B.Paste" user "Package Geometry/Pastemask Bottom")
		(5 "F.SilkS" user "Ref Des/Silkscreen Top")
		(7 "B.SilkS" user "Ref Des/Silkscreen Bottom")
		(1 "F.Mask" user "Board Geometry/Soldermask Top")
		(3 "B.Mask" user "Board Geometry/Soldermask Bottom")
		(17 "Dwgs.User" user "User.Drawings")
		(19 "Cmts.User" user "User.Comments")
		(21 "Eco1.User" user "User.Eco1")
		(23 "Eco2.User" user "User.Eco2")
		(25 "Edge.Cuts" user "Board Geometry/Outline")
		(27 "Margin" user)
		(31 "F.CrtYd" user "Package Geometry/Place Bound Top")
		(29 "B.CrtYd" user "Package Geometry/Place Bound Bottom")
		(35 "F.Fab" user "Ref Des/Assembly Top")
		(33 "B.Fab" user "Ref Des/Assembly Bottom")
	)
	(footprint ""
		(layer "B.Cu")
		(at 460.075788 -383.650998 180)
		(property "Reference" "R2356"
			(at 0 0 0)
			(layer "B.SilkS")
			(hide yes)
			(effects
				(font
					(size 1.27 1.27)
				)
				(justify mirror)
			)
		)
		(property "Value" ""
			(at 0 0 0)
			(layer "B.Fab")
			(effects
				(font
					(size 1.27 1.27)
				)
				(justify mirror)
			)
		)
		(duplicate_pad_numbers_are_jumpers no)
		(fp_line
			(start 0.7874 0.4064)
			(end 0.7874 -0.4064)
			(stroke
				(width 0.1524)
				(type default)
			)
			(layer "B.SilkS")
		)
		(fp_line
			(start 0.7874 -0.4064)
			(end -0.7874 -0.4064)
			(stroke
				(width 0.1524)
				(type default)
			)
			(layer "B.SilkS")
		)
		(fp_line
			(start -0.7874 0.4064)
			(end 0.7874 0.4064)
			(stroke
				(width 0.1524)
				(type default)
			)
			(layer "B.SilkS")
		)
		(fp_line
			(start -0.7874 -0.4064)
			(end -0.7874 0.4064)
			(stroke
				(width 0.1524)
				(type default)
			)
			(layer "B.SilkS")
		)
		(fp_line
			(start 0.67945 0.3048)
			(end 0.67945 -0.305054)
			(stroke
				(width 0.1)
				(type default)
			)
			(layer "B.Fab")
		)
		(fp_line
			(start 0.67945 -0.305054)
			(end 0.12065 -0.305054)
			(stroke
				(width 0.1)
				(type default)
			)
			(layer "B.Fab")
		)
		(fp_line
			(start 0.12065 0.3048)
			(end 0.67945 0.3048)
			(stroke
				(width 0.1)
				(type default)
			)
			(layer "B.Fab")
		)
		(fp_line
			(start 0.12065 0.2794)
			(end 0.12065 0.3048)
			(stroke
				(width 0.1)
				(type default)
			)
			(layer "B.Fab")
		)
		(fp_line
			(start 0.12065 -0.2794)
			(end -0.12065 -0.2794)
			(stroke
				(width 0.1)
				(type default)
			)
			(layer "B.Fab")
		)
		(fp_line
			(start 0.12065 -0.305054)
			(end 0.12065 -0.2794)
			(stroke
				(width 0.1)
				(type default)
			)
			(layer "B.Fab")
		)
		(fp_line
			(start -0.120396 0.3048)
			(end -0.120396 0.2794)
			(stroke
				(width 0.1)
				(type default)
			)
			(layer "B.Fab")
		)
		(fp_line
			(start -0.120396 0.2794)
			(end 0.12065 0.2794)
			(stroke
				(width 0.1)
				(type default)
			)
			(layer "B.Fab")
		)
		(fp_line
			(start -0.12065 -0.2794)
			(end -0.12065 -0.3048)
			(stroke
				(width 0.1)
				(type default)
			)
			(layer "B.Fab")
		)
		(fp_line
			(start -0.12065 -0.3048)
			(end -0.67945 -0.3048)
			(stroke
				(width 0.1)
				(type default)
			)
			(layer "B.Fab")
		)
		(fp_line
			(start -0.67945 0.3048)
			(end -0.120396 0.3048)
			(stroke
				(width 0.1)
				(type default)
			)
			(layer "B.Fab")
		)
		(fp_line
			(start -0.67945 -0.3048)
			(end -0.67945 0.3048)
			(stroke
				(width 0.1)
				(type default)
			)
			(layer "B.Fab")
		)
		(pad "1" smd circle
			(at 0.40005 0)
			(size 0 0)
			(layers "B.Cu" "B.Mask" "B.Paste")
			(net "P5V_AUX_VCC")
		)
		(pad "2" smd circle
			(at -0.40005 0)
			(size 0 0)
			(layers "B.Cu" "B.Mask" "B.Paste")
			(net "PWRGD_P5V_AUX_R")
		)
	)
	(footprint ""
		(layer "B.Cu")
		(at 363.135418 -294.009826 180)
		(property "Reference" "C377"
			(at 0 0 0)
			(layer "B.SilkS")
			(hide yes)
			(effects
				(font
					(size 1.27 1.27)
				)
				(justify mirror)
			)
		)
		(property "Value" ""
			(at 0 0 0)
			(layer "B.Fab")
			(effects
				(font
					(size 1.27 1.27)
				)
				(justify mirror)
			)
		)
		(duplicate_pad_numbers_are_jumpers no)
		(fp_line
			(start 1.524 0.762)
			(end 1.524 -0.762)
			(stroke
				(width 0.1524)
				(type default)
			)
			(layer "B.SilkS")
		)
		(fp_line
			(start 1.524 -0.762)
			(end -1.524 -0.762)
			(stroke
				(width 0.1524)
				(type default)
			)
			(layer "B.SilkS")
		)
		(fp_line
			(start -1.524 0.762)
			(end 1.524 0.762)
			(stroke
				(width 0.1524)
				(type default)
			)
			(layer "B.SilkS")
		)
		(fp_line
			(start -1.524 -0.762)
			(end -1.524 0.762)
			(stroke
				(width 0.1524)
				(type default)
			)
			(layer "B.SilkS")
		)
		(fp_line
			(start 1.1049 0.724916)
			(end -1.1049 0.724916)
			(stroke
				(width 0.1)
				(type default)
			)
			(layer "B.Fab")
		)
		(fp_line
			(start 1.1049 -0.724916)
			(end 1.1049 0.724916)
			(stroke
				(width 0.1)
				(type default)
			)
			(layer "B.Fab")
		)
		(fp_line
			(start -1.1049 0.724916)
			(end -1.1049 -0.724916)
			(stroke
				(width 0.1)
				(type default)
			)
			(layer "B.Fab")
		)
		(fp_line
			(start -1.1049 -0.724916)
			(end 1.1049 -0.724916)
			(stroke
				(width 0.1)
				(type default)
			)
			(layer "B.Fab")
		)
		(pad "1" smd rect
			(at 0.889 0 180)
			(size 1.016 1.27)
			(layers "B.Cu" "B.Mask" "B.Paste")
			(net "PVCCIN_CPU0")
		)
		(pad "2" smd rect
			(at -0.889 0 180)
			(size 1.016 1.27)
			(layers "B.Cu" "B.Mask" "B.Paste")
			(net "GND")
		)
	)
	(footprint ""
		(layer "B.Cu")
		(at 157.504638 -13.762228 90)
		(property "Reference" "R2413"
			(at 0 0 90)
			(layer "B.SilkS")
			(hide yes)
			(effects
				(font
					(size 1.27 1.27)
				)
				(justify mirror)
			)
		)
		(property "Value" ""
			(at 0 0 90)
			(layer "B.Fab")
			(effects
				(font
					(size 1.27 1.27)
				)
				(justify mirror)
			)
		)
		(duplicate_pad_numbers_are_jumpers no)
		(fp_line
			(start 0.7874 -0.4064)
			(end -0.7874 -0.4064)
			(stroke
				(width 0.1524)
				(type default)
			)
			(layer "B.SilkS")
		)
		(fp_line
			(start -0.7874 -0.4064)
			(end -0.7874 0.4064)
			(stroke
				(width 0.1524)
				(type default)
			)
			(layer "B.SilkS")
		)
		(fp_line
			(start 0.7874 0.4064)
			(end 0.7874 -0.4064)
			(stroke
				(width 0.1524)
				(type default)
			)
			(layer "B.SilkS")
		)
		(fp_line
			(start -0.7874 0.4064)
			(end 0.7874 0.4064)
			(stroke
				(width 0.1524)
				(type default)
			)
			(layer "B.SilkS")
		)
		(fp_line
			(start 0.67945 -0.305054)
			(end 0.12065 -0.305054)
			(stroke
				(width 0.1)
				(type default)
			)
			(layer "B.Fab")
		)
		(fp_line
			(start 0.12065 -0.305054)
			(end 0.12065 -0.2794)
			(stroke
				(width 0.1)
				(type default)
			)
			(layer "B.Fab")
		)
		(fp_line
			(start -0.12065 -0.3048)
			(end -0.67945 -0.3048)
			(stroke
				(width 0.1)
				(type default)
			)
			(layer "B.Fab")
		)
		(fp_line
			(start -0.67945 -0.3048)
			(end -0.67945 0.3048)
			(stroke
				(width 0.1)
				(type default)
			)
			(layer "B.Fab")
		)
		(fp_line
			(start 0.12065 -0.2794)
			(end -0.12065 -0.2794)
			(stroke
				(width 0.1)
				(type default)
			)
			(layer "B.Fab")
		)
		(fp_line
			(start -0.12065 -0.2794)
			(end -0.12065 -0.3048)
			(stroke
				(width 0.1)
				(type default)
			)
			(layer "B.Fab")
		)
		(fp_line
			(start 0.12065 0.2794)
			(end 0.12065 0.3048)
			(stroke
				(width 0.1)
				(type default)
			)
			(layer "B.Fab")
		)
		(fp_line
			(start -0.120396 0.2794)
			(end 0.12065 0.2794)
			(stroke
				(width 0.1)
				(type default)
			)
			(layer "B.Fab")
		)
		(fp_line
			(start 0.67945 0.3048)
			(end 0.67945 -0.305054)
			(stroke
				(width 0.1)
				(type default)
			)
			(layer "B.Fab")
		)
		(fp_line
			(start 0.12065 0.3048)
			(end 0.67945 0.3048)
			(stroke
				(width 0.1)
				(type default)
			)
			(layer "B.Fab")
		)
		(fp_line
			(start -0.120396 0.3048)
			(end -0.120396 0.2794)
			(stroke
				(width 0.1)
				(type default)
			)
			(layer "B.Fab")
		)
		(fp_line
			(start -0.67945 0.3048)
			(end -0.120396 0.3048)
			(stroke
				(width 0.1)
				(type default)
			)
			(layer "B.Fab")
		)
		(pad "1" smd circle
			(at 0.40005 0 270)
			(size 0 0)
			(layers "B.Cu" "B.Mask" "B.Paste")
			(net "SMB_2_BMC_GPU_SCL")
		)
		(pad "2" smd circle
			(at -0.40005 0 270)
			(size 0 0)
			(layers "B.Cu" "B.Mask" "B.Paste")
			(net "SMB_PCIE2_3V3AUX_SCL_R0")
		)
	)
)
